# T6G (Grand Teton) — schematic netlist excerpt (pin names and nets, part order shuffled) for the footprints in the layout excerpt that follows; sources: Cadence DE-HDL packaged netlist, KiCad conversion of 04192023_DAF0TMB3IC0_F0TG_MB_C_brd_V02_OCP.brd

PL14  Q_INDUCTOR4P_14  150NH IND  pkg L_TLM117513Q-151QL_11X7-5XA  page 202
  \1\  = SW_PVDDCR_CPU1_P0_SW3
  \2\  = IND_CPU1_P0_CPL2
  \3\  = IND_CPU1_P0_CPL3
  \4\  = PVDDCR_CPU1_P0

(kicad_pcb
	(version 20260206)
	(generator "pcbnew")
	(generator_version "10.0")
	(general
		(thickness 1.6)
		(legacy_teardrops no)
	)
	(paper "A4")
	(title_block
		(title "04192023_DAF0TMB3IC0_F0TG_MB_C_brd_V02_OCP.brd")
		(comment 1 "Grand Teton / footprints 1397-1397 of 8354")
	)
	(layers
		(0 "F.Cu" signal "TOP")
		(4 "In1.Cu" signal "GND")
		(6 "In2.Cu" signal "IN1")
		(8 "In3.Cu" signal "GND1")
		(10 "In4.Cu" signal "IN2")
		(12 "In5.Cu" signal "GND2")
		(14 "In6.Cu" signal "IN3")
		(16 "In7.Cu" signal "GND3")
		(18 "In8.Cu" signal "VCC")
		(20 "In9.Cu" signal "VCC1")
		(22 "In10.Cu" signal "GND4")
		(24 "In11.Cu" signal "IN4")
		(26 "In12.Cu" signal "GND5")
		(28 "In13.Cu" signal "IN5")
		(30 "In14.Cu" signal "GND6")
		(32 "In15.Cu" signal "IN6")
		(34 "In16.Cu" signal "GND7")
		(2 "B.Cu" signal "BOTTOM")
		(9 "F.Adhes" user "F.Adhesive")
		(11 "B.Adhes" user "B.Adhesive")
		(13 "F.Paste" user "Package Geometry/Pastemask Top")
		(15 "B.Paste" user "Package Geometry/Pastemask Bottom")
		(5 "F.SilkS" user "Ref Des/Silkscreen Top")
		(7 "B.SilkS" user "Ref Des/Silkscreen Bottom")
		(1 "F.Mask" user "Board Geometry/Soldermask Top")
		(3 "B.Mask" user "Board Geometry/Soldermask Bottom")
		(17 "Dwgs.User" user "User.Drawings")
		(19 "Cmts.User" user "User.Comments")
		(21 "Eco1.User" user "User.Eco1")
		(23 "Eco2.User" user "User.Eco2")
		(25 "Edge.Cuts" user "Board Geometry/Outline")
		(27 "Margin" user)
		(31 "F.CrtYd" user "Package Geometry/Place Bound Top")
		(29 "B.CrtYd" user "Package Geometry/Place Bound Bottom")
		(35 "F.Fab" user "Ref Des/Assembly Top")
		(33 "B.Fab" user "Ref Des/Assembly Bottom")
	)
	(footprint ""
		(layer "F.Cu")
		(at 318.463676 -325.678038)
		(property "Reference" "PL14"
			(at 3.234944 -15.887446 0)
			(unlocked yes)
			(layer "F.SilkS")
			(effects
				(font
					(size 0.7874 0.5842)
					(thickness 0.1524)
				)
				(justify left)
			)
		)
		(property "Value" ""
			(at 0 0 0)
			(layer "F.Fab")
			(effects
				(font
					(size 1.27 1.27)
				)
			)
		)
		(duplicate_pad_numbers_are_jumpers no)
		(fp_line
			(start -3.750056 -5.500116)
			(end -2.393442 -5.500116)
			(stroke
				(width 0.1524)
				(type default)
			)
			(layer "F.SilkS")
		)
		(fp_line
			(start -3.750056 5.500116)
			(end -3.750056 -5.500116)
			(stroke
				(width 0.1524)
				(type default)
			)
			(layer "F.SilkS")
		)
		(fp_line
			(start -2.393442 5.500116)
			(end -3.750056 5.500116)
			(stroke
				(width 0.1524)
				(type default)
			)
			(layer "F.SilkS")
		)
		(fp_line
			(start 2.393442 5.500116)
			(end 3.750056 5.500116)
			(stroke
				(width 0.1524)
				(type default)
			)
			(layer "F.SilkS")
		)
		(fp_line
			(start 3.750056 -5.500116)
			(end 2.393442 -5.500116)
			(stroke
				(width 0.1524)
				(type default)
			)
			(layer "F.SilkS")
		)
		(fp_line
			(start 3.750056 5.500116)
			(end 3.750056 -5.500116)
			(stroke
				(width 0.1524)
				(type default)
			)
			(layer "F.SilkS")
		)
		(fp_poly
			(pts
				(xy -3.9116 -4.249928) (xy -4.9276 -3.741928) (xy -4.9276 -4.757928)
			)
			(stroke
				(width 0)
				(type default)
			)
			(fill yes)
			(layer "F.SilkS")
		)
		(fp_line
			(start -3.750056 -5.500116)
			(end -3.750056 5.500116)
			(stroke
				(width 0.1)
				(type default)
			)
			(layer "F.Fab")
		)
		(fp_line
			(start -3.750056 5.500116)
			(end 3.750056 5.500116)
			(stroke
				(width 0.1)
				(type default)
			)
			(layer "F.Fab")
		)
		(fp_line
			(start 3.750056 -5.500116)
			(end -3.750056 -5.500116)
			(stroke
				(width 0.1)
				(type default)
			)
			(layer "F.Fab")
		)
		(fp_line
			(start 3.750056 5.500116)
			(end 3.750056 -5.500116)
			(stroke
				(width 0.1)
				(type default)
			)
			(layer "F.Fab")
		)
		(fp_poly
			(pts
				(xy -4.9276 -4.757928) (xy -4.9276 -3.741928) (xy -3.9116 -4.249928)
			)
			(stroke
				(width 0)
				(type default)
			)
			(fill yes)
			(layer "F.Fab")
		)
		(pad "1" smd rect
			(at 0 -4.249928 270)
			(size 2.413 4.5212)
			(layers "F.Cu" "F.Mask" "F.Paste")
			(net "SW_PVDDCR_CPU1_P0_SW3")
		)
		(pad "2" smd rect
			(at 0 -1.175004 270)
			(size 1.3716 4.5212)
			(layers "F.Cu" "F.Mask" "F.Paste")
			(net "IND_CPU1_P0_CPL2")
		)
		(pad "3" smd rect
			(at 0 1.175004 270)
			(size 1.3716 4.5212)
			(layers "F.Cu" "F.Mask" "F.Paste")
			(net "IND_CPU1_P0_CPL3")
		)
		(pad "4" smd rect
			(at 0 4.249928 270)
			(size 2.413 4.5212)
			(layers "F.Cu" "F.Mask" "F.Paste")
			(net "PVDDCR_CPU1_P0")
		)
	)
)
